(kicad_pcb
	(version 20241229)
	(generator "pcbnew")
	(generator_version "9.0")
	(general
		(thickness 1.294)
		(legacy_teardrops no)
	)
	(paper "A3")
	(title_block
		(title "Kintex 410T devboard")
		(date "2024-04-03")
		(rev "1.1.2")
		(comment 9 "footprints 361-366 of 975")
	)
	(layers
		(0 "F.Cu" mixed)
		(4 "In1.Cu" power)
		(6 "In2.Cu" power)
		(8 "In3.Cu" mixed)
		(10 "In4.Cu" power)
		(12 "In5.Cu" mixed)
		(14 "In6.Cu" power)
		(16 "In7.Cu" mixed)
		(18 "In8.Cu" power)
		(2 "B.Cu" mixed)
		(9 "F.Adhes" user "F.Adhesive")
		(11 "B.Adhes" user "B.Adhesive")
		(13 "F.Paste" user)
		(15 "B.Paste" user)
		(5 "F.SilkS" user "F.Silkscreen")
		(7 "B.SilkS" user "B.Silkscreen")
		(1 "F.Mask" user)
		(3 "B.Mask" user)
		(17 "Dwgs.User" user "User.Drawings")
		(19 "Cmts.User" user "User.Comments")
		(21 "Eco1.User" user "User.Eco1")
		(23 "Eco2.User" user "User.Eco2")
		(25 "Edge.Cuts" user)
		(27 "Margin" user)
		(31 "F.CrtYd" user "F.Courtyard")
		(29 "B.CrtYd" user "B.Courtyard")
		(35 "F.Fab" user)
		(33 "B.Fab" user)
	)
	(footprint "antmicro-footprints:DFN3538"
		(layer "F.Cu")
		(at 236.9 174.5 180)
		(property "Reference" "D4"
			(at 0.7 -3.3 0)
			(unlocked yes)
			(layer "F.SilkS")
			(effects
				(font
					(size 0.7 0.7)
					(thickness 0.15)
				)
				(justify left bottom)
			)
		)
		(property "Value" "CD-MMBL110S"
			(at 0 3.5 180)
			(unlocked yes)
			(layer "F.Fab")
			(effects
				(font
					(size 0.7 0.7)
					(thickness 0.15)
				)
				(justify left bottom)
			)
		)
		(property "Description" "TVS diode"
			(at 0 0 180)
			(layer "F.Fab")
			(hide yes)
			(effects
				(font
					(size 1.27 1.27)
					(thickness 0.15)
				)
			)
		)
		(property "Author" "Antmicro"
			(at 473.8 349 0)
			(layer "F.Fab")
			(hide yes)
			(effects
				(font
					(size 1 1)
					(thickness 0.15)
				)
			)
		)
		(property "License" "Apache-2.0"
			(at 473.8 349 0)
			(layer "F.Fab")
			(hide yes)
			(effects
				(font
					(size 1 1)
					(thickness 0.15)
				)
			)
		)
		(property "MPN" "CD-MMBL110S"
			(at 473.8 349 0)
			(layer "F.Fab")
			(hide yes)
			(effects
				(font
					(size 1 1)
					(thickness 0.15)
				)
			)
		)
		(property "Manufacturer" "Bourns"
			(at 473.8 349 0)
			(layer "F.Fab")
			(hide yes)
			(effects
				(font
					(size 1 1)
					(thickness 0.15)
				)
			)
		)
		(sheetname "Power supply")
		(sheetfile "power-supply.kicad_sch")
		(attr smd)
		(fp_line
			(start 1.8 -2)
			(end 1.8 2.05)
			(stroke
				(width 0.15)
				(type solid)
			)
			(layer "F.SilkS")
		)
		(fp_line
			(start 1.6 2.05)
			(end 1.8 2.05)
			(stroke
				(width 0.15)
				(type solid)
			)
			(layer "F.SilkS")
		)
		(fp_line
			(start 1.6 -2)
			(end 1.8 -2)
			(stroke
				(width 0.15)
				(type solid)
			)
			(layer "F.SilkS")
		)
		(fp_line
			(start 0.9 -2.301)
			(end 0.598 -2.301)
			(stroke
				(width 0.15)
				(type solid)
			)
			(layer "F.SilkS")
		)
		(fp_line
			(start 0.748 -2.452)
			(end 0.748 -2.15)
			(stroke
				(width 0.15)
				(type solid)
			)
			(layer "F.SilkS")
		)
		(fp_line
			(start -0.902 -2.25)
			(end -0.6 -2.25)
			(stroke
				(width 0.15)
				(type solid)
			)
			(layer "F.SilkS")
		)
		(fp_line
			(start -0.95 2.05)
			(end 0.95 2.05)
			(stroke
				(width 0.15)
				(type solid)
			)
			(layer "F.SilkS")
		)
		(fp_line
			(start -0.95 -2)
			(end 0.95 -2)
			(stroke
				(width 0.15)
				(type solid)
			)
			(layer "F.SilkS")
		)
		(fp_line
			(start -1.8 2.05)
			(end -1.6 2.05)
			(stroke
				(width 0.15)
				(type solid)
			)
			(layer "F.SilkS")
		)
		(fp_line
			(start -1.8 -1.5)
			(end -1.8 2.05)
			(stroke
				(width 0.15)
				(type solid)
			)
			(layer "F.SilkS")
		)
		(fp_rect
			(start -2.1 -2.6)
			(end 2.1 2.6)
			(stroke
				(width 0.05)
				(type solid)
			)
			(fill no)
			(layer "F.CrtYd")
		)
		(fp_line
			(start -1.051 -2)
			(end -1.801 -1.25)
			(stroke
				(width 0.15)
				(type solid)
			)
			(layer "F.Fab")
		)
		(fp_rect
			(start 1.8 2.048)
			(end -1.8 -2)
			(stroke
				(width 0.15)
				(type solid)
			)
			(fill no)
			(layer "F.Fab")
		)
		(fp_text user "~"
			(at -0.31 2.59 180)
			(unlocked yes)
			(layer "F.SilkS")
			(effects
				(font
					(size 0.7 0.7)
					(thickness 0.15)
				)
				(justify left bottom)
			)
		)
		(pad "1" smd roundrect
			(at -1.27 -1.85 270)
			(size 1.4 0.48)
			(layers "F.Cu" "F.Mask" "F.Paste")
			(roundrect_rratio 0.25)
			(net 756 "Net-(D4-Pad1)")
			(pinfunction "1")
			(pintype "output")
		)
		(pad "2" smd roundrect
			(at 1.27 -1.85 270)
			(size 1.4 0.48)
			(layers "F.Cu" "F.Mask" "F.Paste")
			(roundrect_rratio 0.25)
			(net 757 "Net-(D4-Pad2)")
			(pinfunction "2")
			(pintype "output")
		)
		(pad "3" smd roundrect
			(at -1.27 1.85 270)
			(size 1.4 0.48)
			(layers "F.Cu" "F.Mask" "F.Paste")
			(roundrect_rratio 0.25)
			(net 759 "/HDMI + Ethernet/POE_GBE.VC2")
			(pinfunction "3")
			(pintype "input")
		)
		(pad "4" smd roundrect
			(at 1.27 1.85 270)
			(size 1.4 0.48)
			(layers "F.Cu" "F.Mask" "F.Paste")
			(roundrect_rratio 0.25)
			(net 758 "/HDMI + Ethernet/POE_GBE.VC1")
			(pinfunction "4")
			(pintype "input")
		)
	)
	(footprint "antmicro-footprints:R_0402_1005Metric"
		(layer "F.Cu")
		(at 246.6 141.6 -90)
		(descr "Resistor SMD 0402")
		(tags "resistor SMD 0402")
		(property "Reference" "R164"
			(at 1.65 -6.35 270)
			(layer "F.SilkS")
			(effects
				(font
					(size 0.7 0.7)
					(thickness 0.15)
				)
				(justify left bottom)
			)
		)
		(property "Value" "R_33R_0402"
			(at 0 1.4 270)
			(layer "F.Fab")
			(effects
				(font
					(size 0.7 0.7)
					(thickness 0.15)
				)
				(justify left bottom)
			)
		)
		(property "Description" "SMD Chip Resistor, 33 ohm, ± 1%, 62.5 mW, 0402 [1005 Metric], Thick Film, General Purpose"
			(at 0 0 270)
			(layer "F.Fab")
			(hide yes)
			(effects
				(font
					(size 1.27 1.27)
					(thickness 0.15)
				)
			)
		)
		(property "Author" "Antmicro"
			(at 105 388.2 0)
			(layer "F.Fab")
			(hide yes)
			(effects
				(font
					(size 1 1)
					(thickness 0.15)
				)
			)
		)
		(property "License" "Apache-2.0"
			(at 105 388.2 0)
			(layer "F.Fab")
			(hide yes)
			(effects
				(font
					(size 1 1)
					(thickness 0.15)
				)
			)
		)
		(property "MPN" "CR0402-FX-33R0GLF"
			(at 105 388.2 0)
			(layer "F.Fab")
			(hide yes)
			(effects
				(font
					(size 1 1)
					(thickness 0.15)
				)
			)
		)
		(property "Manufacturer" "Bourns"
			(at 105 388.2 0)
			(layer "F.Fab")
			(hide yes)
			(effects
				(font
					(size 1 1)
					(thickness 0.15)
				)
			)
		)
		(property "Tolerance" "1%"
			(at 105 388.2 0)
			(layer "F.Fab")
			(hide yes)
			(effects
				(font
					(size 1 1)
					(thickness 0.15)
				)
			)
		)
		(property "Val" "33R"
			(at 105 388.2 0)
			(layer "F.Fab")
			(hide yes)
			(effects
				(font
					(size 1 1)
					(thickness 0.15)
				)
			)
		)
		(sheetname "USB PHY")
		(sheetfile "usb-phy.kicad_sch")
		(attr smd)
		(fp_rect
			(start -0.925 -0.47)
			(end 0.925 0.47)
			(stroke
				(width 0.05)
				(type default)
			)
			(fill no)
			(layer "F.CrtYd")
		)
		(fp_rect
			(start -0.5 -0.25)
			(end 0.5 0.25)
			(stroke
				(width 0.15)
				(type solid)
			)
			(fill no)
			(layer "F.Fab")
		)
		(pad "1" smd roundrect
			(at -0.48 0 270)
			(size 0.59 0.64)
			(layers "F.Cu" "F.Mask" "F.Paste")
			(roundrect_rratio 0.25)
			(net 924 "/USB PHY/FTDI_UART1_RX")
			(pintype "passive")
		)
		(pad "2" smd roundrect
			(at 0.48 0 270)
			(size 0.59 0.64)
			(layers "F.Cu" "F.Mask" "F.Paste")
			(roundrect_rratio 0.25)
			(net 54 "/FPGA Bank 12 & 13/UART1.TX")
			(pintype "passive")
		)
	)
	(footprint "antmicro-footprints:R_0402_1005Metric"
		(layer "F.Cu")
		(at 225.1 111.2)
		(descr "Resistor SMD 0402")
		(tags "resistor SMD 0402")
		(property "Reference" "R95"
			(at -3.65 0.4 0)
			(layer "F.SilkS")
			(effects
				(font
					(size 0.7 0.7)
					(thickness 0.15)
				)
				(justify left bottom)
			)
		)
		(property "Value" "R_10k_0402"
			(at 0 1.4 0)
			(layer "F.Fab")
			(effects
				(font
					(size 0.7 0.7)
					(thickness 0.15)
				)
				(justify left bottom)
			)
		)
		(property "Description" "SMD Chip Resistor, 10 kohm, ± 1%, 62.5 mW, 0402 [1005 Metric], Thick Film, General Purpose"
			(at 0 0 0)
			(layer "F.Fab")
			(hide yes)
			(effects
				(font
					(size 1.27 1.27)
					(thickness 0.15)
				)
			)
		)
		(property "Author" "Antmicro"
			(at 0 0 0)
			(layer "F.Fab")
			(hide yes)
			(effects
				(font
					(size 1 1)
					(thickness 0.15)
				)
			)
		)
		(property "License" "Apache-2.0"
			(at 0 0 0)
			(layer "F.Fab")
			(hide yes)
			(effects
				(font
					(size 1 1)
					(thickness 0.15)
				)
			)
		)
		(property "MPN" "CR0402-FX-1002GLF"
			(at 0 0 0)
			(layer "F.Fab")
			(hide yes)
			(effects
				(font
					(size 1 1)
					(thickness 0.15)
				)
			)
		)
		(property "Manufacturer" "Bourns"
			(at 0 0 0)
			(layer "F.Fab")
			(hide yes)
			(effects
				(font
					(size 1 1)
					(thickness 0.15)
				)
			)
		)
		(property "Tolerance" "1%"
			(at 0 0 0)
			(layer "F.Fab")
			(hide yes)
			(effects
				(font
					(size 1 1)
					(thickness 0.15)
				)
			)
		)
		(property "Val" "10k"
			(at 0 0 0)
			(layer "F.Fab")
			(hide yes)
			(effects
				(font
					(size 1 1)
					(thickness 0.15)
				)
			)
		)
		(sheetname "SPI Flash + SD Card")
		(sheetfile "spi-flash.kicad_sch")
		(attr smd)
		(fp_rect
			(start -0.925 -0.47)
			(end 0.925 0.47)
			(stroke
				(width 0.05)
				(type default)
			)
			(fill no)
			(layer "F.CrtYd")
		)
		(fp_rect
			(start -0.5 -0.25)
			(end 0.5 0.25)
			(stroke
				(width 0.15)
				(type solid)
			)
			(fill no)
			(layer "F.Fab")
		)
		(pad "1" smd roundrect
			(at -0.48 0)
			(size 0.59 0.64)
			(layers "F.Cu" "F.Mask" "F.Paste")
			(roundrect_rratio 0.25)
			(net 420 "/FPGA Bank 16 & 17/USR_FLASH_1.~{CS}")
			(pintype "passive")
		)
		(pad "2" smd roundrect
			(at 0.48 0)
			(size 0.59 0.64)
			(layers "F.Cu" "F.Mask" "F.Paste")
			(roundrect_rratio 0.25)
			(net 3 "VCC_USR_B")
			(pintype "passive")
		)
	)
	(footprint "antmicro-footprints:C_0603_1608Metric"
		(layer "F.Cu")
		(at 188.1 169.249 -90)
		(descr "Capacitor SMD 0603")
		(tags "capacitor 0603")
		(property "Reference" "C207"
			(at -3.849 -0.4 90)
			(layer "F.SilkS")
			(effects
				(font
					(size 0.7 0.7)
					(thickness 0.15)
				)
				(justify right bottom)
			)
		)
		(property "Value" "C_1u_25V_0603"
			(at 0 1.6 90)
			(layer "F.Fab")
			(effects
				(font
					(size 0.7 0.7)
					(thickness 0.15)
				)
				(justify right bottom)
			)
		)
		(property "Description" "SMD Multilayer Ceramic Capacitor, 1 µF, 25 V, 0603 [1608 Metric], ± 10%, X5R, CL"
			(at 0 0 270)
			(layer "F.Fab")
			(hide yes)
			(effects
				(font
					(size 1.27 1.27)
					(thickness 0.15)
				)
			)
		)
		(property "Author" "Antmicro"
			(at 18.851 357.349 0)
			(layer "F.Fab")
			(hide yes)
			(effects
				(font
					(size 1 1)
					(thickness 0.15)
				)
			)
		)
		(property "Dielectric" ""
			(at 18.851 357.349 0)
			(layer "F.Fab")
			(hide yes)
			(effects
				(font
					(size 1 1)
					(thickness 0.15)
				)
			)
		)
		(property "License" "Apache-2.0"
			(at 18.851 357.349 0)
			(layer "F.Fab")
			(hide yes)
			(effects
				(font
					(size 1 1)
					(thickness 0.15)
				)
			)
		)
		(property "MPN" "CL10A105KA8NNNC"
			(at 18.851 357.349 0)
			(layer "F.Fab")
			(hide yes)
			(effects
				(font
					(size 1 1)
					(thickness 0.15)
				)
			)
		)
		(property "Manufacturer" "Samsung Electro-Mechanics"
			(at 18.851 357.349 0)
			(layer "F.Fab")
			(hide yes)
			(effects
				(font
					(size 1 1)
					(thickness 0.15)
				)
			)
		)
		(property "Val" "1u"
			(at 18.851 357.349 0)
			(layer "F.Fab")
			(hide yes)
			(effects
				(font
					(size 1 1)
					(thickness 0.15)
				)
			)
		)
		(property "Voltage" "25V"
			(at 18.851 357.349 0)
			(layer "F.Fab")
			(hide yes)
			(effects
				(font
					(size 1 1)
					(thickness 0.15)
				)
			)
		)
		(sheetname "Power supply")
		(sheetfile "power-supply.kicad_sch")
		(attr smd)
		(fp_line
			(start -0.15 0.4)
			(end 0.15 0.4)
			(stroke
				(width 0.15)
				(type solid)
			)
			(layer "F.SilkS")
		)
		(fp_line
			(start -0.15 -0.4)
			(end 0.15 -0.4)
			(stroke
				(width 0.15)
				(type solid)
			)
			(layer "F.SilkS")
		)
		(fp_rect
			(start -1.25 -0.65)
			(end 1.25 0.65)
			(stroke
				(width 0.05)
				(type solid)
			)
			(fill no)
			(layer "F.CrtYd")
		)
		(fp_rect
			(start -0.8 -0.4)
			(end 0.8 0.4)
			(stroke
				(width 0.15)
				(type solid)
			)
			(fill no)
			(layer "F.Fab")
		)
		(pad "1" smd roundrect
			(at -0.7 0 270)
			(size 0.8 1)
			(layers "F.Cu" "F.Mask" "F.Paste")
			(roundrect_rratio 0.2)
			(net 1 "GND")
			(pintype "passive")
		)
		(pad "2" smd roundrect
			(at 0.7 0 270)
			(size 0.8 1)
			(layers "F.Cu" "F.Mask" "F.Paste")
			(roundrect_rratio 0.2)
			(net 702 "VDC")
			(pintype "passive")
		)
	)
	(footprint "antmicro-footprints:C_0603_1608Metric"
		(layer "F.Cu")
		(at 177.5 164)
		(descr "Capacitor SMD 0603")
		(tags "capacitor 0603")
		(property "Reference" "C331"
			(at 1 0.4 0)
			(layer "F.SilkS")
			(effects
				(font
					(size 0.7 0.7)
					(thickness 0.15)
				)
				(justify left bottom)
			)
		)
		(property "Value" "C_22u_0603"
			(at 0 1.6 0)
			(layer "F.Fab")
			(effects
				(font
					(size 0.7 0.7)
					(thickness 0.15)
				)
				(justify left bottom)
			)
		)
		(property "Description" "SMD Multilayer Ceramic Capacitor, 22 µF, 6.3 V, 0603 [1608 Metric], ± 20%, X5R, GRM Series"
			(at 0 0 0)
			(layer "F.Fab")
			(hide yes)
			(effects
				(font
					(size 1.27 1.27)
					(thickness 0.15)
				)
			)
		)
		(property "Author" "Antmicro"
			(at 0 0 0)
			(layer "F.Fab")
			(hide yes)
			(effects
				(font
					(size 1 1)
					(thickness 0.15)
				)
			)
		)
		(property "Dielectric" ""
			(at 0 0 0)
			(layer "F.Fab")
			(hide yes)
			(effects
				(font
					(size 1 1)
					(thickness 0.15)
				)
			)
		)
		(property "License" "Apache-2.0"
			(at 0 0 0)
			(layer "F.Fab")
			(hide yes)
			(effects
				(font
					(size 1 1)
					(thickness 0.15)
				)
			)
		)
		(property "MPN" "GRM188R60J226MEA0D"
			(at 0 0 0)
			(layer "F.Fab")
			(hide yes)
			(effects
				(font
					(size 1 1)
					(thickness 0.15)
				)
			)
		)
		(property "Manufacturer" "Murata"
			(at 0 0 0)
			(layer "F.Fab")
			(hide yes)
			(effects
				(font
					(size 1 1)
					(thickness 0.15)
				)
			)
		)
		(property "Val" "22u"
			(at 0 0 0)
			(layer "F.Fab")
			(hide yes)
			(effects
				(font
					(size 1 1)
					(thickness 0.15)
				)
			)
		)
		(property "Voltage" ""
			(at 0 0 0)
			(layer "F.Fab")
			(hide yes)
			(effects
				(font
					(size 1 1)
					(thickness 0.15)
				)
			)
		)
		(sheetname "DC-DC Converters")
		(sheetfile "dc-dc.kicad_sch")
		(attr smd)
		(fp_line
			(start -0.15 -0.4)
			(end 0.15 -0.4)
			(stroke
				(width 0.15)
				(type solid)
			)
			(layer "F.SilkS")
		)
		(fp_line
			(start -0.15 0.4)
			(end 0.15 0.4)
			(stroke
				(width 0.15)
				(type solid)
			)
			(layer "F.SilkS")
		)
		(fp_rect
			(start -1.25 -0.65)
			(end 1.25 0.65)
			(stroke
				(width 0.05)
				(type solid)
			)
			(fill no)
			(layer "F.CrtYd")
		)
		(fp_rect
			(start -0.8 -0.4)
			(end 0.8 0.4)
			(stroke
				(width 0.15)
				(type solid)
			)
			(fill no)
			(layer "F.Fab")
		)
		(pad "1" smd roundrect
			(at -0.7 0)
			(size 0.8 1)
			(layers "F.Cu" "F.Mask" "F.Paste")
			(roundrect_rratio 0.2)
			(net 1 "GND")
			(pintype "passive")
		)
		(pad "2" smd roundrect
			(at 0.7 0)
			(size 0.8 1)
			(layers "F.Cu" "F.Mask" "F.Paste")
			(roundrect_rratio 0.2)
			(net 736 "/DC-DC Converters/3V3_local_2")
			(pintype "passive")
		)
	)
	(footprint "antmicro-footprints:C_2220_5650Metric"
		(layer "F.Cu")
		(at 234.075 185.575 90)
		(descr "Capacitor SMD 2220")
		(tags "capacitor SMD 2220")
		(property "Reference" "C199"
			(at 3.675 -1.425 180)
			(layer "F.SilkS")
			(effects
				(font
					(size 0.7 0.7)
					(thickness 0.15)
				)
				(justify left bottom)
			)
		)
		(property "Value" "C_22u_100V_2220"
			(at 0 3.9 90)
			(layer "F.Fab")
			(effects
				(font
					(size 0.7 0.7)
					(thickness 0.15)
				)
				(justify left bottom)
			)
		)
		(property "Description" "SMT Multilayer Ceramic Capacitor, 22 µF, 100 V, 2220 [5750 Metric], ± 20%, X7S, C"
			(at 0 0 90)
			(layer "F.Fab")
			(hide yes)
			(effects
				(font
					(size 1.27 1.27)
					(thickness 0.15)
				)
			)
		)
		(property "Author" "Antmicro"
			(at 419.65 -48.5 0)
			(layer "F.Fab")
			(hide yes)
			(effects
				(font
					(size 1 1)
					(thickness 0.15)
				)
			)
		)
		(property "Dielectric" "X7S"
			(at 419.65 -48.5 0)
			(layer "F.Fab")
			(hide yes)
			(effects
				(font
					(size 1 1)
					(thickness 0.15)
				)
			)
		)
		(property "License" "Apache-2.0"
			(at 419.65 -48.5 0)
			(layer "F.Fab")
			(hide yes)
			(effects
				(font
					(size 1 1)
					(thickness 0.15)
				)
			)
		)
		(property "MPN" "C5750X7S2A226M280KB"
			(at 419.65 -48.5 0)
			(layer "F.Fab")
			(hide yes)
			(effects
				(font
					(size 1 1)
					(thickness 0.15)
				)
			)
		)
		(property "Manufacturer" "TDK"
			(at 419.65 -48.5 0)
			(layer "F.Fab")
			(hide yes)
			(effects
				(font
					(size 1 1)
					(thickness 0.15)
				)
			)
		)
		(property "Val" "22u"
			(at 419.65 -48.5 0)
			(layer "F.Fab")
			(hide yes)
			(effects
				(font
					(size 1 1)
					(thickness 0.15)
				)
			)
		)
		(property "Voltage" "100V"
			(at 419.65 -48.5 0)
			(layer "F.Fab")
			(hide yes)
			(effects
				(font
					(size 1 1)
					(thickness 0.15)
				)
			)
		)
		(sheetname "Power supply")
		(sheetfile "power-supply.kicad_sch")
		(attr smd)
		(fp_line
			(start -1.415 -2.61)
			(end 1.415 -2.61)
			(stroke
				(width 0.15)
				(type solid)
			)
			(layer "F.SilkS")
		)
		(fp_line
			(start -1.415 2.61)
			(end 1.415 2.61)
			(stroke
				(width 0.15)
				(type solid)
			)
			(layer "F.SilkS")
		)
		(fp_rect
			(start -3.7 -2.95)
			(end 3.7 2.95)
			(stroke
				(width 0.05)
				(type solid)
			)
			(fill no)
			(layer "F.CrtYd")
		)
		(fp_rect
			(start -2.85 -2.5)
			(end 2.85 2.5)
			(stroke
				(width 0.15)
				(type solid)
			)
			(fill no)
			(layer "F.Fab")
		)
		(pad "1" smd roundrect
			(at -2.55 0 90)
			(size 1.8 5.4)
			(layers "F.Cu" "F.Mask" "F.Paste")
			(roundrect_rratio 0.138889)
			(net 699 "GNDD")
			(pintype "passive")
		)
		(pad "2" smd roundrect
			(at 2.55 0 90)
			(size 1.8 5.4)
			(layers "F.Cu" "F.Mask" "F.Paste")
			(roundrect_rratio 0.138889)
			(net 698 "/Power supply/VDD")
			(pintype "passive")
		)
	)
)
